(kicad_pcb
	(version 20260206)
	(generator "pcbnew")
	(generator_version "10.0")
	(general
		(thickness 1.21888)
		(legacy_teardrops no)
	)
	(paper "A4")
	(title_block
		(title "timecard-v7 — TimeCard-DC-V7_EXP.PcbDoc")
		(comment 1 "Time Appliance Project (Time Card) / footprints 92-102 of 160")
	)
	(layers
		(0 "F.Cu" signal "TOP")
		(4 "In1.Cu" signal "SGND")
		(6 "In2.Cu" signal "IN1")
		(8 "In3.Cu" signal "IN2")
		(10 "In4.Cu" signal "SGND1")
		(2 "B.Cu" signal "BOTTOM")
		(9 "F.Adhes" user "F.Adhesive")
		(11 "B.Adhes" user "B.Adhesive")
		(13 "F.Paste" user "Top Paste")
		(15 "B.Paste" user "Bottom Paste")
		(5 "F.SilkS" user "Top Overlay")
		(7 "B.SilkS" user "Bottom Overlay")
		(1 "F.Mask" user "Top Solder")
		(3 "B.Mask" user "Bottom Solder")
		(17 "Dwgs.User" user "User.Drawings")
		(19 "Cmts.User" user "User.Comments")
		(21 "Eco1.User" user "User.Eco1")
		(23 "Eco2.User" user "User.Eco2")
		(25 "Edge.Cuts" user)
		(27 "Margin" user)
		(31 "F.CrtYd" user "Top Courtyard")
		(29 "B.CrtYd" user "Bottom Courtyard")
		(35 "F.Fab" user "Top Component Center")
		(33 "B.Fab" user "Bottom Component Center")
	)
	(footprint "Vault:CAPC1608X90X35NL10T15"
		(layer "F.Cu")
		(at 208.7745 109.1942)
		(property "Reference" "C20"
			(at -1.336 -0.346345 180)
			(unlocked yes)
			(layer "F.SilkS")
			(effects
				(font
					(size 0.762 0.762)
					(thickness 0.2286)
				)
				(justify left bottom)
			)
		)
		(property "Value" "0.033uF"
			(at 6.5525 3.91939 0)
			(unlocked yes)
			(layer "F.SilkS")
			(hide yes)
			(effects
				(font
					(size 1.524 1.524)
					(thickness 0.254)
				)
				(justify left bottom)
			)
		)
		(sheetname "POWER")
		(sheetfile "POWER.kicad_sch")
		(duplicate_pad_numbers_are_jumpers no)
		(pad "1" smd rect
			(at -0.675 0 90)
			(size 0.95 0.85)
			(layers "F.Cu" "F.Mask" "F.Paste")
			(net "NetC20_1")
		)
		(pad "2" smd rect
			(at 0.675 0 90)
			(size 0.95 0.85)
			(layers "F.Cu" "F.Mask" "F.Paste")
			(net "NetC20_2")
		)
	)
	(footprint "Vault:RESC1608X55X25NL10T15"
		(layer "F.Cu")
		(at 77.8761 108.6162 180)
		(property "Reference" "R33"
			(at -0.2286 1.473069 0)
			(unlocked yes)
			(layer "F.SilkS")
			(effects
				(font
					(size 0.762 0.762)
					(thickness 0.2286)
				)
			)
		)
		(property "Value" "49.9R"
			(at -2.911602 3.21199 90)
			(unlocked yes)
			(layer "F.SilkS")
			(hide yes)
			(effects
				(font
					(size 1.524 1.524)
					(thickness 0.254)
				)
			)
		)
		(sheetname "USER_IO")
		(sheetfile "USER_IO.kicad_sch")
		(duplicate_pad_numbers_are_jumpers no)
		(pad "1" smd rect
			(at -0.7 0 270)
			(size 0.9 0.7)
			(layers "F.Cu" "F.Mask" "F.Paste")
			(net "NetR33_1")
		)
		(pad "2" smd rect
			(at 0.7 0 270)
			(size 0.9 0.7)
			(layers "F.Cu" "F.Mask" "F.Paste")
			(net "NetAN2_1")
		)
	)
	(footprint "Resistors:RESC1005X04N"
		(layer "F.Cu")
		(at 119.4761 145.5786 -90)
		(property "Reference" "R23"
			(at 1.27491 0.808535 90)
			(unlocked yes)
			(layer "F.SilkS")
			(effects
				(font
					(size 0.762 0.762)
					(thickness 0.2286)
				)
				(justify left bottom)
			)
		)
		(property "Value" "ERJ-2GE0R00X"
			(at 3.42519 0.2413 0)
			(unlocked yes)
			(layer "F.SilkS")
			(hide yes)
			(effects
				(font
					(size 1.524 1.524)
					(thickness 0.254)
				)
				(justify left bottom)
			)
		)
		(sheetname "PCIe_JTAG")
		(sheetfile "PCIe_JTAG.kicad_sch")
		(duplicate_pad_numbers_are_jumpers no)
		(pad "1" smd rect
			(at -0.425 0)
			(size 0.6 0.65)
			(layers "F.Cu" "F.Mask" "F.Paste")
			(net "PRSNT")
		)
		(pad "2" smd rect
			(at 0.425 0)
			(size 0.6 0.65)
			(layers "F.Cu" "F.Mask" "F.Paste")
			(net "NetP2_B17")
		)
	)
	(footprint "Resistors:RESC1608X50N"
		(layer "F.Cu")
		(at 91.9361 122.0786 180)
		(property "Reference" "R22"
			(at 1.06 0.906655 0)
			(unlocked yes)
			(layer "F.SilkS")
			(effects
				(font
					(size 0.762 0.762)
					(thickness 0.2286)
				)
				(justify left bottom)
			)
		)
		(property "Value" "ERJ-3EKF4701V"
			(at 0.4445 -3.72999 0)
			(unlocked yes)
			(layer "F.SilkS")
			(hide yes)
			(effects
				(font
					(size 1.524 1.524)
					(thickness 0.254)
				)
				(justify left bottom)
			)
		)
		(sheetname "PCIe_JTAG")
		(sheetfile "PCIe_JTAG.kicad_sch")
		(duplicate_pad_numbers_are_jumpers no)
		(fp_line
			(start 0 -0.5)
			(end 0 0.5)
			(stroke
				(width 0.1524)
				(type solid)
			)
			(layer "F.SilkS")
		)
		(pad "1" smd rect
			(at -0.69 0 270)
			(size 1 0.72)
			(layers "F.Cu" "F.Mask" "F.Paste")
			(net "PCIE_PERST")
		)
		(pad "2" smd rect
			(at 0.69 0 270)
			(size 1 0.72)
			(layers "F.Cu" "F.Mask" "F.Paste")
			(net "+3.3V")
		)
	)
	(footprint "Passives:FUSM1608X60N"
		(layer "F.Cu")
		(at 228.6261 118.5162 180)
		(property "Reference" "F1"
			(at -0.6 0.806655 0)
			(unlocked yes)
			(layer "F.SilkS")
			(effects
				(font
					(size 0.762 0.762)
					(thickness 0.2286)
				)
				(justify left bottom)
			)
		)
		(property "Value" "FUSE_0603_2.00A"
			(at 2.1929 -5.08039 0)
			(unlocked yes)
			(layer "F.SilkS")
			(hide yes)
			(effects
				(font
					(size 1.524 1.524)
					(thickness 0.254)
				)
				(justify left bottom)
			)
		)
		(sheetname "POWER")
		(sheetfile "POWER.kicad_sch")
		(duplicate_pad_numbers_are_jumpers no)
		(fp_line
			(start 0 -0.5)
			(end 0 0.5)
			(stroke
				(width 0.1524)
				(type solid)
			)
			(layer "F.SilkS")
		)
		(pad "1" smd rect
			(at -0.69 0 270)
			(size 1 0.72)
			(layers "F.Cu" "F.Mask" "F.Paste")
			(net "NetD12_1")
		)
		(pad "2" smd rect
			(at 0.69 0 270)
			(size 1 0.72)
			(layers "F.Cu" "F.Mask" "F.Paste")
			(net "+12V")
		)
	)
	(footprint "Vault:AMPH-901-143-6RFX_V"
		(layer "F.Cu")
		(at 60.9761 108.5782 180)
		(property "Reference" "AN2"
			(at -5.917345 2.55101 90)
			(unlocked yes)
			(layer "F.SilkS")
			(effects
				(font
					(size 0.762 0.762)
					(thickness 0.2286)
				)
				(justify left bottom)
			)
		)
		(property "Value" "901-143-6RFX"
			(at 4.6101 -2.05359 0)
			(unlocked yes)
			(layer "F.SilkS")
			(hide yes)
			(effects
				(font
					(size 1.524 1.524)
					(thickness 0.254)
				)
				(justify left bottom)
			)
		)
		(sheetname "USER_IO")
		(sheetfile "USER_IO.kicad_sch")
		(duplicate_pad_numbers_are_jumpers no)
		(fp_line
			(start 3.5 -1.38)
			(end 3.5 1.38)
			(stroke
				(width 0.2)
				(type solid)
			)
			(layer "F.SilkS")
		)
		(fp_line
			(start 1.38 3.5)
			(end -1.38 3.5)
			(stroke
				(width 0.2)
				(type solid)
			)
			(layer "F.SilkS")
		)
		(fp_line
			(start 1.38 -3.5)
			(end -1.38 -3.5)
			(stroke
				(width 0.2)
				(type solid)
			)
			(layer "F.SilkS")
		)
		(fp_line
			(start -3.5 -1.38)
			(end -3.5 1.38)
			(stroke
				(width 0.2)
				(type solid)
			)
			(layer "F.SilkS")
		)
		(pad "1" thru_hole rect
			(at 0 0 180)
			(size 2 2)
			(drill 1.5)
			(layers "*.Cu" "*.Mask")
			(remove_unused_layers no)
			(net "NetAN2_1")
		)
		(pad "2" thru_hole circle
			(at -2.54 -2.54 180)
			(size 2.2 2.2)
			(drill 1.7)
			(layers "*.Cu" "*.Mask")
			(remove_unused_layers no)
			(net "GND")
			(thermal_bridge_angle 90)
		)
		(pad "3" thru_hole circle
			(at -2.54 2.54 180)
			(size 2.2 2.2)
			(drill 1.7)
			(layers "*.Cu" "*.Mask")
			(remove_unused_layers no)
			(net "GND")
			(thermal_bridge_angle 90)
		)
		(pad "4" thru_hole circle
			(at 2.54 2.54 180)
			(size 2.2 2.2)
			(drill 1.7)
			(layers "*.Cu" "*.Mask")
			(remove_unused_layers no)
			(net "GND")
			(thermal_bridge_angle 90)
		)
		(pad "5" thru_hole circle
			(at 2.54 -2.54 180)
			(size 2.2 2.2)
			(drill 1.7)
			(layers "*.Cu" "*.Mask")
			(remove_unused_layers no)
			(net "GND")
			(thermal_bridge_angle 90)
		)
	)
	(footprint "Vault:RESC1608X55X30NL15T15"
		(layer "F.Cu")
		(at 166.1261 88.5786 90)
		(property "Reference" "R26"
			(at 3.14763 0.055781 90)
			(unlocked yes)
			(layer "F.SilkS")
			(effects
				(font
					(size 0.762 0.762)
					(thickness 0.2286)
				)
			)
		)
		(property "Value" "4.7K"
			(at -3.114802 2.39944 0)
			(unlocked yes)
			(layer "F.SilkS")
			(hide yes)
			(effects
				(font
					(size 1.524 1.524)
					(thickness 0.254)
				)
			)
		)
		(sheetname "GPS_IMU_SENSORS")
		(sheetfile "GPS_IMU_SENSORS.kicad_sch")
		(duplicate_pad_numbers_are_jumpers no)
		(pad "1" smd rect
			(at -0.75 0 180)
			(size 0.95 0.95)
			(layers "F.Cu" "F.Mask" "F.Paste")
			(net "SDA")
		)
		(pad "2" smd rect
			(at 0.75 0 180)
			(size 0.95 0.95)
			(layers "F.Cu" "F.Mask" "F.Paste")
			(net "+3.3V")
		)
	)
	(footprint "Vault:CAPC1608X87X45ML20T05"
		(layer "F.Cu")
		(at 80.3761 139.6162 -90)
		(property "Reference" "C29"
			(at 2.7714 -0.026931 90)
			(unlocked yes)
			(layer "F.SilkS")
			(effects
				(font
					(size 0.762 0.762)
					(thickness 0.2286)
				)
			)
		)
		(property "Value" "0.1uF"
			(at 2.09443 2.657602 270)
			(unlocked yes)
			(layer "F.SilkS")
			(hide yes)
			(effects
				(font
					(size 1.524 1.524)
					(thickness 0.254)
				)
			)
		)
		(sheetname "USER_IO")
		(sheetfile "USER_IO.kicad_sch")
		(duplicate_pad_numbers_are_jumpers no)
		(pad "1" smd rect
			(at -0.7 0)
			(size 1.1 1.05)
			(layers "F.Cu" "F.Mask" "F.Paste")
			(net "+3.3V")
		)
		(pad "2" smd rect
			(at 0.7 0)
			(size 1.1 1.05)
			(layers "F.Cu" "F.Mask" "F.Paste")
			(net "GND")
		)
	)
	(footprint "Passives:IND_PM124SH"
		(layer "F.Cu")
		(at 210.9261 99.2162 180)
		(property "Reference" "L2"
			(at -4.7 -7.493345 0)
			(unlocked yes)
			(layer "F.SilkS")
			(effects
				(font
					(size 0.762 0.762)
					(thickness 0.2286)
				)
				(justify left bottom)
			)
		)
		(property "Value" "PM124SH-100M-RC"
			(at 11.1787 -11.07019 0)
			(unlocked yes)
			(layer "F.SilkS")
			(hide yes)
			(effects
				(font
					(size 1.524 1.524)
					(thickness 0.254)
				)
				(justify left bottom)
			)
		)
		(sheetname "POWER")
		(sheetfile "POWER.kicad_sch")
		(duplicate_pad_numbers_are_jumpers no)
		(fp_line
			(start 6.681 6.4)
			(end -6.681 6.4)
			(stroke
				(width 0.254)
				(type solid)
			)
			(layer "F.SilkS")
		)
		(fp_line
			(start 6.681 -6.4)
			(end 6.681 6.4)
			(stroke
				(width 0.254)
				(type solid)
			)
			(layer "F.SilkS")
		)
		(fp_line
			(start 6.681 -6.4)
			(end -6.681 -6.4)
			(stroke
				(width 0.254)
				(type solid)
			)
			(layer "F.SilkS")
		)
		(fp_line
			(start -6.681 -6.4)
			(end -6.681 6.4)
			(stroke
				(width 0.254)
				(type solid)
			)
			(layer "F.SilkS")
		)
		(pad "1" smd rect
			(at -4.85 0 180)
			(size 2.9 5.4)
			(layers "F.Cu" "F.Mask" "F.Paste")
			(net "+3.3V")
		)
		(pad "2" smd rect
			(at 4.85 0 180)
			(size 2.9 5.4)
			(layers "F.Cu" "F.Mask" "F.Paste")
			(net "NetC3_2")
		)
	)
	(footprint "Connectors:SAMTEC_HTST-105-01-L-DV-A"
		(layer "F.Cu")
		(at 212.8061 138.9462)
		(property "Reference" "U5"
			(at -9.58 -5.136655 0)
			(unlocked yes)
			(layer "F.SilkS")
			(effects
				(font
					(size 0.762 0.762)
					(thickness 0.2286)
				)
				(justify left bottom)
			)
		)
		(property "Value" "HTST-105-01-L-DV-A"
			(at -0.5217 18.18359 0)
			(unlocked yes)
			(layer "F.SilkS")
			(hide yes)
			(effects
				(font
					(size 1.524 1.524)
					(thickness 0.254)
				)
				(justify left bottom)
			)
		)
		(sheetname "PCIe_JTAG")
		(sheetfile "PCIe_JTAG.kicad_sch")
		(duplicate_pad_numbers_are_jumpers no)
		(fp_line
			(start -10.16 -4.635)
			(end -6.065 -4.635)
			(stroke
				(width 0.2)
				(type solid)
			)
			(layer "F.SilkS")
		)
		(fp_line
			(start -10.16 4.635)
			(end -10.16 -4.635)
			(stroke
				(width 0.2)
				(type solid)
			)
			(layer "F.SilkS")
		)
		(fp_line
			(start -10.16 4.635)
			(end -6.065 4.635)
			(stroke
				(width 0.2)
				(type solid)
			)
			(layer "F.SilkS")
		)
		(fp_line
			(start 6.065 -4.635)
			(end 10.16 -4.635)
			(stroke
				(width 0.2)
				(type solid)
			)
			(layer "F.SilkS")
		)
		(fp_line
			(start 6.065 4.635)
			(end 10.16 4.635)
			(stroke
				(width 0.2)
				(type solid)
			)
			(layer "F.SilkS")
		)
		(fp_line
			(start 10.16 4.635)
			(end 10.16 -4.635)
			(stroke
				(width 0.2)
				(type solid)
			)
			(layer "F.SilkS")
		)
		(fp_circle
			(center -7.62 5.715)
			(end -7.62 5.08)
			(stroke
				(width 0.2)
				(type solid)
			)
			(fill no)
			(layer "F.SilkS")
		)
		(pad "" np_thru_hole circle
			(at -3.81 0)
			(size 1.676 1.676)
			(drill 1.676)
			(layers "*.Cu" "*.Mask")
			(thermal_bridge_angle 90)
		)
		(pad "" np_thru_hole circle
			(at 3.81 0)
			(size 1.676 1.676)
			(drill 1.676)
			(layers "*.Cu" "*.Mask")
			(thermal_bridge_angle 90)
		)
		(pad "1" smd rect
			(at -5.08 3.43)
			(size 1.27 5.08)
			(layers "F.Cu" "F.Mask" "F.Paste")
			(net "NetR18_2")
		)
		(pad "2" smd rect
			(at -5.08 -3.43)
			(size 1.27 5.08)
			(layers "F.Cu" "F.Mask" "F.Paste")
			(net "GND")
		)
		(pad "3" smd rect
			(at -2.54 3.43)
			(size 1.27 5.08)
			(layers "F.Cu" "F.Mask" "F.Paste")
			(net "NetR19_2")
		)
		(pad "4" smd rect
			(at -2.54 -3.43)
			(size 1.27 5.08)
			(layers "F.Cu" "F.Mask" "F.Paste")
			(net "+3.3V")
		)
		(pad "5" smd rect
			(at 0 3.43)
			(size 1.27 5.08)
			(layers "F.Cu" "F.Mask" "F.Paste")
			(net "NetR20_2")
		)
		(pad "6" smd rect
			(at 0 -3.43)
			(size 1.27 5.08)
			(layers "F.Cu" "F.Mask" "F.Paste")
			(net "+3.3V")
		)
		(pad "7" smd rect
			(at 2.54 3.43)
			(size 1.27 5.08)
			(layers "F.Cu" "F.Mask" "F.Paste")
		)
		(pad "8" smd rect
			(at 2.54 -3.43)
			(size 1.27 5.08)
			(layers "F.Cu" "F.Mask" "F.Paste")
		)
		(pad "9" smd rect
			(at 5.08 3.43)
			(size 1.27 5.08)
			(layers "F.Cu" "F.Mask" "F.Paste")
			(net "NetR21_2")
		)
		(pad "10" smd rect
			(at 5.08 -3.43)
			(size 1.27 5.08)
			(layers "F.Cu" "F.Mask" "F.Paste")
			(net "GND")
		)
	)
	(footprint "Vault:CAPC1608X87X45ML20T05"
		(layer "F.Cu")
		(at 215.9637 90.4662 90)
		(property "Reference" "C9"
			(at 4.2 -0.493345 270)
			(unlocked yes)
			(layer "F.SilkS")
			(effects
				(font
					(size 0.762 0.762)
					(thickness 0.2286)
				)
				(justify left bottom)
			)
		)
		(property "Value" "0.1uF"
			(at -11.53319 0.6471 0)
			(unlocked yes)
			(layer "F.SilkS")
			(hide yes)
			(effects
				(font
					(size 1.524 1.524)
					(thickness 0.254)
				)
				(justify left bottom)
			)
		)
		(sheetname "POWER")
		(sheetfile "POWER.kicad_sch")
		(duplicate_pad_numbers_are_jumpers no)
		(pad "1" smd rect
			(at -0.7 0 180)
			(size 1.1 1.05)
			(layers "F.Cu" "F.Mask" "F.Paste")
			(net "GND")
		)
		(pad "2" smd rect
			(at 0.7 0 180)
			(size 1.1 1.05)
			(layers "F.Cu" "F.Mask" "F.Paste")
			(net "+3.3V")
		)
	)
)
